# T6G (Grand Teton) — schematic netlist excerpt (pin names and nets, part order shuffled) for the footprints in the layout excerpt that follows; sources: Cadence DE-HDL packaged netlist, KiCad conversion of 04192023_DAF0TMB3IC0_F0TG_MB_C_brd_V02_OCP.brd

R184  Q_RES  0 5% CHIP  pkg 0402LF  page 82 : A = CPU0_CORETYPE1 ; B = FM_CPU0_CORETYPE1
PL50  Q_INDUCTOR  120NH/69A IND  pkg SMLF  page 196 : \1\ = GND ; \2\ = IND_CPU0_P0_CPL0
R6042  Q_RES  10K 5% CHIP  pkg 0402LF  page 167 : A = P3V3_AUX ; B = PU_FPGA_DEBUG_SW_SPARE

(kicad_pcb
	(version 20260206)
	(generator "pcbnew")
	(generator_version "10.0")
	(general
		(thickness 1.6)
		(legacy_teardrops no)
	)
	(paper "A4")
	(title_block
		(title "04192023_DAF0TMB3IC0_F0TG_MB_C_brd_V02_OCP.brd")
		(comment 1 "Grand Teton / footprints 2951-2953 of 8354")
	)
	(layers
		(0 "F.Cu" signal "TOP")
		(4 "In1.Cu" signal "GND")
		(6 "In2.Cu" signal "IN1")
		(8 "In3.Cu" signal "GND1")
		(10 "In4.Cu" signal "IN2")
		(12 "In5.Cu" signal "GND2")
		(14 "In6.Cu" signal "IN3")
		(16 "In7.Cu" signal "GND3")
		(18 "In8.Cu" signal "VCC")
		(20 "In9.Cu" signal "VCC1")
		(22 "In10.Cu" signal "GND4")
		(24 "In11.Cu" signal "IN4")
		(26 "In12.Cu" signal "GND5")
		(28 "In13.Cu" signal "IN5")
		(30 "In14.Cu" signal "GND6")
		(32 "In15.Cu" signal "IN6")
		(34 "In16.Cu" signal "GND7")
		(2 "B.Cu" signal "BOTTOM")
		(9 "F.Adhes" user "F.Adhesive")
		(11 "B.Adhes" user "B.Adhesive")
		(13 "F.Paste" user "Package Geometry/Pastemask Top")
		(15 "B.Paste" user "Package Geometry/Pastemask Bottom")
		(5 "F.SilkS" user "Ref Des/Silkscreen Top")
		(7 "B.SilkS" user "Ref Des/Silkscreen Bottom")
		(1 "F.Mask" user "Board Geometry/Soldermask Top")
		(3 "B.Mask" user "Board Geometry/Soldermask Bottom")
		(17 "Dwgs.User" user "User.Drawings")
		(19 "Cmts.User" user "User.Comments")
		(21 "Eco1.User" user "User.Eco1")
		(23 "Eco2.User" user "User.Eco2")
		(25 "Edge.Cuts" user "Board Geometry/Outline")
		(27 "Margin" user)
		(31 "F.CrtYd" user "Package Geometry/Place Bound Top")
		(29 "B.CrtYd" user "Package Geometry/Place Bound Bottom")
		(35 "F.Fab" user "Ref Des/Assembly Top")
		(33 "B.Fab" user "Ref Des/Assembly Bottom")
	)
	(footprint ""
		(layer "F.Cu")
		(at 420.75735 -37.277548)
		(property "Reference" "R6042"
			(at 0 0 0)
			(layer "F.SilkS")
			(hide yes)
			(effects
				(font
					(size 1.27 1.27)
				)
			)
		)
		(property "Value" ""
			(at 0 0 0)
			(layer "F.Fab")
			(effects
				(font
					(size 1.27 1.27)
				)
			)
		)
		(duplicate_pad_numbers_are_jumpers no)
		(fp_line
			(start -0.7874 -0.4064)
			(end 0.7874 -0.4064)
			(stroke
				(width 0.1524)
				(type default)
			)
			(layer "F.SilkS")
		)
		(fp_line
			(start -0.7874 0.4064)
			(end -0.7874 -0.4064)
			(stroke
				(width 0.1524)
				(type default)
			)
			(layer "F.SilkS")
		)
		(fp_line
			(start 0.7874 -0.4064)
			(end 0.7874 0.4064)
			(stroke
				(width 0.1524)
				(type default)
			)
			(layer "F.SilkS")
		)
		(fp_line
			(start 0.7874 0.4064)
			(end -0.7874 0.4064)
			(stroke
				(width 0.1524)
				(type default)
			)
			(layer "F.SilkS")
		)
		(fp_line
			(start -0.67945 -0.305054)
			(end -0.12065 -0.305054)
			(stroke
				(width 0.1)
				(type default)
			)
			(layer "F.Fab")
		)
		(fp_line
			(start -0.67945 0.3048)
			(end -0.67945 -0.305054)
			(stroke
				(width 0.1)
				(type default)
			)
			(layer "F.Fab")
		)
		(fp_line
			(start -0.12065 -0.305054)
			(end -0.12065 -0.2794)
			(stroke
				(width 0.1)
				(type default)
			)
			(layer "F.Fab")
		)
		(fp_line
			(start -0.12065 -0.2794)
			(end 0.12065 -0.2794)
			(stroke
				(width 0.1)
				(type default)
			)
			(layer "F.Fab")
		)
		(fp_line
			(start -0.12065 0.2794)
			(end -0.12065 0.3048)
			(stroke
				(width 0.1)
				(type default)
			)
			(layer "F.Fab")
		)
		(fp_line
			(start -0.12065 0.3048)
			(end -0.67945 0.3048)
			(stroke
				(width 0.1)
				(type default)
			)
			(layer "F.Fab")
		)
		(fp_line
			(start 0.120396 0.2794)
			(end -0.12065 0.2794)
			(stroke
				(width 0.1)
				(type default)
			)
			(layer "F.Fab")
		)
		(fp_line
			(start 0.120396 0.3048)
			(end 0.120396 0.2794)
			(stroke
				(width 0.1)
				(type default)
			)
			(layer "F.Fab")
		)
		(fp_line
			(start 0.12065 -0.3048)
			(end 0.67945 -0.3048)
			(stroke
				(width 0.1)
				(type default)
			)
			(layer "F.Fab")
		)
		(fp_line
			(start 0.12065 -0.2794)
			(end 0.12065 -0.3048)
			(stroke
				(width 0.1)
				(type default)
			)
			(layer "F.Fab")
		)
		(fp_line
			(start 0.67945 -0.3048)
			(end 0.67945 0.3048)
			(stroke
				(width 0.1)
				(type default)
			)
			(layer "F.Fab")
		)
		(fp_line
			(start 0.67945 0.3048)
			(end 0.120396 0.3048)
			(stroke
				(width 0.1)
				(type default)
			)
			(layer "F.Fab")
		)
		(pad "1" smd circle
			(at -0.40005 0)
			(size 0 0)
			(layers "F.Cu" "F.Mask" "F.Paste")
			(net "P3V3_AUX")
		)
		(pad "2" smd circle
			(at 0.40005 0)
			(size 0 0)
			(layers "F.Cu" "F.Mask" "F.Paste")
			(net "PU_FPGA_DEBUG_SW_SPARE")
		)
	)
	(footprint ""
		(layer "F.Cu")
		(at 340.162388 -165.803834 90)
		(property "Reference" "PL50"
			(at 0.439166 -4.093718 90)
			(unlocked yes)
			(layer "F.SilkS")
			(effects
				(font
					(size 0.7874 0.5842)
					(thickness 0.1524)
				)
				(justify left)
			)
		)
		(property "Value" ""
			(at 0 0 90)
			(layer "F.Fab")
			(effects
				(font
					(size 1.27 1.27)
				)
			)
		)
		(duplicate_pad_numbers_are_jumpers no)
		(fp_line
			(start 3.24993 -3.24993)
			(end 3.24993 -2.2352)
			(stroke
				(width 0.1524)
				(type default)
			)
			(layer "F.SilkS")
		)
		(fp_line
			(start -3.24993 -3.24993)
			(end 3.24993 -3.24993)
			(stroke
				(width 0.1524)
				(type default)
			)
			(layer "F.SilkS")
		)
		(fp_line
			(start -3.24993 -2.2352)
			(end -3.24993 -3.24993)
			(stroke
				(width 0.1524)
				(type default)
			)
			(layer "F.SilkS")
		)
		(fp_line
			(start 3.24993 2.2352)
			(end 3.24993 3.24993)
			(stroke
				(width 0.1524)
				(type default)
			)
			(layer "F.SilkS")
		)
		(fp_line
			(start 3.24993 3.24993)
			(end -3.24993 3.24993)
			(stroke
				(width 0.1524)
				(type default)
			)
			(layer "F.SilkS")
		)
		(fp_line
			(start -3.24993 3.24993)
			(end -3.24993 2.2352)
			(stroke
				(width 0.1524)
				(type default)
			)
			(layer "F.SilkS")
		)
		(fp_line
			(start 3.24993 -3.24993)
			(end 3.24993 3.24993)
			(stroke
				(width 0.1)
				(type default)
			)
			(layer "F.Fab")
		)
		(fp_line
			(start -3.24993 -3.24993)
			(end 3.24993 -3.24993)
			(stroke
				(width 0.1)
				(type default)
			)
			(layer "F.Fab")
		)
		(fp_line
			(start 3.24993 3.24993)
			(end -3.24993 3.24993)
			(stroke
				(width 0.1)
				(type default)
			)
			(layer "F.Fab")
		)
		(fp_line
			(start -3.24993 3.24993)
			(end -3.24993 -3.24993)
			(stroke
				(width 0.1)
				(type default)
			)
			(layer "F.Fab")
		)
		(pad "1" smd rect
			(at -2.29997 0 90)
			(size 2.0066 4.2164)
			(layers "F.Cu" "F.Mask" "F.Paste")
			(net "GND")
		)
		(pad "2" smd rect
			(at 2.29997 0 90)
			(size 2.0066 4.2164)
			(layers "F.Cu" "F.Mask" "F.Paste")
			(net "IND_CPU0_P0_CPL0")
		)
	)
	(footprint ""
		(layer "F.Cu")
		(at 189.865 -100.294948 90)
		(property "Reference" "R184"
			(at 0 0 90)
			(layer "F.SilkS")
			(hide yes)
			(effects
				(font
					(size 1.27 1.27)
				)
			)
		)
		(property "Value" ""
			(at 0 0 90)
			(layer "F.Fab")
			(effects
				(font
					(size 1.27 1.27)
				)
			)
		)
		(duplicate_pad_numbers_are_jumpers no)
		(fp_line
			(start 0.7874 -0.4064)
			(end 0.7874 0.4064)
			(stroke
				(width 0.1524)
				(type default)
			)
			(layer "F.SilkS")
		)
		(fp_line
			(start -0.7874 -0.4064)
			(end 0.7874 -0.4064)
			(stroke
				(width 0.1524)
				(type default)
			)
			(layer "F.SilkS")
		)
		(fp_line
			(start 0.7874 0.4064)
			(end -0.7874 0.4064)
			(stroke
				(width 0.1524)
				(type default)
			)
			(layer "F.SilkS")
		)
		(fp_line
			(start -0.7874 0.4064)
			(end -0.7874 -0.4064)
			(stroke
				(width 0.1524)
				(type default)
			)
			(layer "F.SilkS")
		)
		(fp_line
			(start -0.12065 -0.305054)
			(end -0.12065 -0.2794)
			(stroke
				(width 0.1)
				(type default)
			)
			(layer "F.Fab")
		)
		(fp_line
			(start -0.67945 -0.305054)
			(end -0.12065 -0.305054)
			(stroke
				(width 0.1)
				(type default)
			)
			(layer "F.Fab")
		)
		(fp_line
			(start 0.67945 -0.3048)
			(end 0.67945 0.3048)
			(stroke
				(width 0.1)
				(type default)
			)
			(layer "F.Fab")
		)
		(fp_line
			(start 0.12065 -0.3048)
			(end 0.67945 -0.3048)
			(stroke
				(width 0.1)
				(type default)
			)
			(layer "F.Fab")
		)
		(fp_line
			(start 0.12065 -0.2794)
			(end 0.12065 -0.3048)
			(stroke
				(width 0.1)
				(type default)
			)
			(layer "F.Fab")
		)
		(fp_line
			(start -0.12065 -0.2794)
			(end 0.12065 -0.2794)
			(stroke
				(width 0.1)
				(type default)
			)
			(layer "F.Fab")
		)
		(fp_line
			(start 0.120396 0.2794)
			(end -0.12065 0.2794)
			(stroke
				(width 0.1)
				(type default)
			)
			(layer "F.Fab")
		)
		(fp_line
			(start -0.12065 0.2794)
			(end -0.12065 0.3048)
			(stroke
				(width 0.1)
				(type default)
			)
			(layer "F.Fab")
		)
		(fp_line
			(start 0.67945 0.3048)
			(end 0.120396 0.3048)
			(stroke
				(width 0.1)
				(type default)
			)
			(layer "F.Fab")
		)
		(fp_line
			(start 0.120396 0.3048)
			(end 0.120396 0.2794)
			(stroke
				(width 0.1)
				(type default)
			)
			(layer "F.Fab")
		)
		(fp_line
			(start -0.12065 0.3048)
			(end -0.67945 0.3048)
			(stroke
				(width 0.1)
				(type default)
			)
			(layer "F.Fab")
		)
		(fp_line
			(start -0.67945 0.3048)
			(end -0.67945 -0.305054)
			(stroke
				(width 0.1)
				(type default)
			)
			(layer "F.Fab")
		)
		(pad "1" smd circle
			(at -0.40005 0 90)
			(size 0 0)
			(layers "F.Cu" "F.Mask" "F.Paste")
			(net "CPU0_CORETYPE1")
		)
		(pad "2" smd circle
			(at 0.40005 0 90)
			(size 0 0)
			(layers "F.Cu" "F.Mask" "F.Paste")
			(net "FM_CPU0_CORETYPE1")
		)
	)
)
